# S9S_MB_2U (Grand Teton) — schematic netlist excerpt (pin names and nets, part order shuffled) for the footprints in the layout excerpt that follows; sources: Cadence DE-HDL packaged netlist, KiCad conversion of 03242023_DA0F0TMBIJ0_F0T_Motherboard_J_brd_V01_OCP.brd

C5236  Q_CAP  0.1UF 25V 10% EMPTY  pkg 0402  page 152 : A = PD_U5201_VREG ; B = GND
R3875  Q_RES  49.9 1% CHIP  pkg 0402LF  page 82 : A = I3C_SPD_DDRABCD_CPU0_LVC1_SCL_R ; B = I3C_SPD_DDRABCD_CPU0_LVC1_SCL

(kicad_pcb
	(version 20260206)
	(generator "pcbnew")
	(generator_version "10.0")
	(general
		(thickness 1.6)
		(legacy_teardrops no)
	)
	(paper "A4")
	(title_block
		(title "03242023_DA0F0TMBIJ0_F0T_Motherboard_J_brd_V01_OCP.brd")
		(comment 1 "Grand Teton / footprints 4444-4445 of 6105")
	)
	(layers
		(0 "F.Cu" signal "TOP")
		(4 "In1.Cu" signal "GND")
		(6 "In2.Cu" signal "IN1")
		(8 "In3.Cu" signal "GND1")
		(10 "In4.Cu" signal "IN2")
		(12 "In5.Cu" signal "GND2")
		(14 "In6.Cu" signal "IN3")
		(16 "In7.Cu" signal "GND3")
		(18 "In8.Cu" signal "VCC")
		(20 "In9.Cu" signal "VCC1")
		(22 "In10.Cu" signal "GND4")
		(24 "In11.Cu" signal "IN4")
		(26 "In12.Cu" signal "GND5")
		(28 "In13.Cu" signal "IN5")
		(30 "In14.Cu" signal "GND6")
		(32 "In15.Cu" signal "IN6")
		(34 "In16.Cu" signal "GND7")
		(2 "B.Cu" signal "BOTTOM")
		(9 "F.Adhes" user "F.Adhesive")
		(11 "B.Adhes" user "B.Adhesive")
		(13 "F.Paste" user "Package Geometry/Pastemask Top")
		(15 "B.Paste" user "Package Geometry/Pastemask Bottom")
		(5 "F.SilkS" user "Ref Des/Silkscreen Top")
		(7 "B.SilkS" user "Ref Des/Silkscreen Bottom")
		(1 "F.Mask" user "Board Geometry/Soldermask Top")
		(3 "B.Mask" user "Board Geometry/Soldermask Bottom")
		(17 "Dwgs.User" user "User.Drawings")
		(19 "Cmts.User" user "User.Comments")
		(21 "Eco1.User" user "User.Eco1")
		(23 "Eco2.User" user "User.Eco2")
		(25 "Edge.Cuts" user "Board Geometry/Outline")
		(27 "Margin" user)
		(31 "F.CrtYd" user "Package Geometry/Place Bound Top")
		(29 "B.CrtYd" user "Package Geometry/Place Bound Bottom")
		(35 "F.Fab" user "Ref Des/Assembly Top")
		(33 "B.Fab" user "Ref Des/Assembly Bottom")
	)
	(footprint ""
		(layer "B.Cu")
		(at 16.237712 -112.693958 180)
		(property "Reference" "C5236"
			(at 0 0 0)
			(layer "B.SilkS")
			(hide yes)
			(effects
				(font
					(size 1.27 1.27)
				)
				(justify mirror)
			)
		)
		(property "Value" ""
			(at 0 0 0)
			(layer "B.Fab")
			(effects
				(font
					(size 1.27 1.27)
				)
				(justify mirror)
			)
		)
		(duplicate_pad_numbers_are_jumpers no)
		(fp_line
			(start 0.7874 0.4064)
			(end 0.7874 -0.4064)
			(stroke
				(width 0.1524)
				(type default)
			)
			(layer "B.SilkS")
		)
		(fp_line
			(start 0.7874 -0.4064)
			(end -0.7874 -0.4064)
			(stroke
				(width 0.1524)
				(type default)
			)
			(layer "B.SilkS")
		)
		(fp_line
			(start -0.7874 0.4064)
			(end 0.7874 0.4064)
			(stroke
				(width 0.1524)
				(type default)
			)
			(layer "B.SilkS")
		)
		(fp_line
			(start -0.7874 -0.4064)
			(end -0.7874 0.4064)
			(stroke
				(width 0.1524)
				(type default)
			)
			(layer "B.SilkS")
		)
		(fp_line
			(start 0.67945 0.3048)
			(end 0.67945 -0.305054)
			(stroke
				(width 0.1)
				(type default)
			)
			(layer "B.Fab")
		)
		(fp_line
			(start 0.67945 -0.305054)
			(end 0.12065 -0.305054)
			(stroke
				(width 0.1)
				(type default)
			)
			(layer "B.Fab")
		)
		(fp_line
			(start 0.12065 0.3048)
			(end 0.67945 0.3048)
			(stroke
				(width 0.1)
				(type default)
			)
			(layer "B.Fab")
		)
		(fp_line
			(start 0.12065 0.2794)
			(end 0.12065 0.3048)
			(stroke
				(width 0.1)
				(type default)
			)
			(layer "B.Fab")
		)
		(fp_line
			(start 0.12065 -0.2794)
			(end -0.12065 -0.2794)
			(stroke
				(width 0.1)
				(type default)
			)
			(layer "B.Fab")
		)
		(fp_line
			(start 0.12065 -0.305054)
			(end 0.12065 -0.2794)
			(stroke
				(width 0.1)
				(type default)
			)
			(layer "B.Fab")
		)
		(fp_line
			(start -0.120396 0.3048)
			(end -0.120396 0.2794)
			(stroke
				(width 0.1)
				(type default)
			)
			(layer "B.Fab")
		)
		(fp_line
			(start -0.120396 0.2794)
			(end 0.12065 0.2794)
			(stroke
				(width 0.1)
				(type default)
			)
			(layer "B.Fab")
		)
		(fp_line
			(start -0.12065 -0.2794)
			(end -0.12065 -0.3048)
			(stroke
				(width 0.1)
				(type default)
			)
			(layer "B.Fab")
		)
		(fp_line
			(start -0.12065 -0.3048)
			(end -0.67945 -0.3048)
			(stroke
				(width 0.1)
				(type default)
			)
			(layer "B.Fab")
		)
		(fp_line
			(start -0.67945 0.3048)
			(end -0.120396 0.3048)
			(stroke
				(width 0.1)
				(type default)
			)
			(layer "B.Fab")
		)
		(fp_line
			(start -0.67945 -0.3048)
			(end -0.67945 0.3048)
			(stroke
				(width 0.1)
				(type default)
			)
			(layer "B.Fab")
		)
		(pad "1" smd circle
			(at 0.40005 0)
			(size 0 0)
			(layers "B.Cu" "B.Mask" "B.Paste")
			(net "PD_U5201_VREG")
		)
		(pad "2" smd circle
			(at -0.40005 0)
			(size 0 0)
			(layers "B.Cu" "B.Mask" "B.Paste")
			(net "GND")
		)
	)
	(footprint ""
		(layer "B.Cu")
		(at 299.609002 -317.243714 90)
		(property "Reference" "R3875"
			(at 0 0 90)
			(layer "B.SilkS")
			(hide yes)
			(effects
				(font
					(size 1.27 1.27)
				)
				(justify mirror)
			)
		)
		(property "Value" ""
			(at 0 0 90)
			(layer "B.Fab")
			(effects
				(font
					(size 1.27 1.27)
				)
				(justify mirror)
			)
		)
		(duplicate_pad_numbers_are_jumpers no)
		(fp_line
			(start 0.7874 -0.4064)
			(end -0.7874 -0.4064)
			(stroke
				(width 0.1524)
				(type default)
			)
			(layer "B.SilkS")
		)
		(fp_line
			(start -0.7874 -0.4064)
			(end -0.7874 0.4064)
			(stroke
				(width 0.1524)
				(type default)
			)
			(layer "B.SilkS")
		)
		(fp_line
			(start 0.7874 0.4064)
			(end 0.7874 -0.4064)
			(stroke
				(width 0.1524)
				(type default)
			)
			(layer "B.SilkS")
		)
		(fp_line
			(start -0.7874 0.4064)
			(end 0.7874 0.4064)
			(stroke
				(width 0.1524)
				(type default)
			)
			(layer "B.SilkS")
		)
		(fp_line
			(start 0.67945 -0.305054)
			(end 0.12065 -0.305054)
			(stroke
				(width 0.1)
				(type default)
			)
			(layer "B.Fab")
		)
		(fp_line
			(start 0.12065 -0.305054)
			(end 0.12065 -0.2794)
			(stroke
				(width 0.1)
				(type default)
			)
			(layer "B.Fab")
		)
		(fp_line
			(start -0.12065 -0.3048)
			(end -0.67945 -0.3048)
			(stroke
				(width 0.1)
				(type default)
			)
			(layer "B.Fab")
		)
		(fp_line
			(start -0.67945 -0.3048)
			(end -0.67945 0.3048)
			(stroke
				(width 0.1)
				(type default)
			)
			(layer "B.Fab")
		)
		(fp_line
			(start 0.12065 -0.2794)
			(end -0.12065 -0.2794)
			(stroke
				(width 0.1)
				(type default)
			)
			(layer "B.Fab")
		)
		(fp_line
			(start -0.12065 -0.2794)
			(end -0.12065 -0.3048)
			(stroke
				(width 0.1)
				(type default)
			)
			(layer "B.Fab")
		)
		(fp_line
			(start 0.12065 0.2794)
			(end 0.12065 0.3048)
			(stroke
				(width 0.1)
				(type default)
			)
			(layer "B.Fab")
		)
		(fp_line
			(start -0.120396 0.2794)
			(end 0.12065 0.2794)
			(stroke
				(width 0.1)
				(type default)
			)
			(layer "B.Fab")
		)
		(fp_line
			(start 0.67945 0.3048)
			(end 0.67945 -0.305054)
			(stroke
				(width 0.1)
				(type default)
			)
			(layer "B.Fab")
		)
		(fp_line
			(start 0.12065 0.3048)
			(end 0.67945 0.3048)
			(stroke
				(width 0.1)
				(type default)
			)
			(layer "B.Fab")
		)
		(fp_line
			(start -0.120396 0.3048)
			(end -0.120396 0.2794)
			(stroke
				(width 0.1)
				(type default)
			)
			(layer "B.Fab")
		)
		(fp_line
			(start -0.67945 0.3048)
			(end -0.120396 0.3048)
			(stroke
				(width 0.1)
				(type default)
			)
			(layer "B.Fab")
		)
		(pad "1" smd circle
			(at 0.40005 0 270)
			(size 0 0)
			(layers "B.Cu" "B.Mask" "B.Paste")
			(net "I3C_SPD_DDRABCD_CPU0_LVC1_SCL_R")
		)
		(pad "2" smd circle
			(at -0.40005 0 270)
			(size 0 0)
			(layers "B.Cu" "B.Mask" "B.Paste")
			(net "I3C_SPD_DDRABCD_CPU0_LVC1_SCL")
		)
	)
)
